(kicad_pcb
	(version 20260206)
	(generator "pcbnew")
	(generator_version "10.0")
	(general
		(thickness 1.6)
		(legacy_teardrops no)
	)
	(paper "A4")
	(title_block
		(title "pdpb — Lightning_PDPB_BRD.brd")
		(comment 1 "Lightning (Wiwynn / Facebook NVMe JBOF) / footprints 815-821 of 1140")
	)
	(layers
		(0 "F.Cu" signal "TOP")
		(4 "In1.Cu" signal "L2GND")
		(6 "In2.Cu" signal "L3")
		(8 "In3.Cu" signal "L4VCC")
		(10 "In4.Cu" signal "L5VCC")
		(12 "In5.Cu" signal "L6")
		(14 "In6.Cu" signal "L7GND")
		(2 "B.Cu" signal "BOTTOM")
		(9 "F.Adhes" user "F.Adhesive")
		(11 "B.Adhes" user "B.Adhesive")
		(13 "F.Paste" user "Package Geometry/Pastemask Top")
		(15 "B.Paste" user "Package Geometry/Pastemask Bottom")
		(5 "F.SilkS" user "Ref Des/Silkscreen Top")
		(7 "B.SilkS" user "Ref Des/Silkscreen Bottom")
		(1 "F.Mask" user "Board Geometry/Soldermask Top")
		(3 "B.Mask" user "Board Geometry/Soldermask Bottom")
		(17 "Dwgs.User" user "User.Drawings")
		(19 "Cmts.User" user "User.Comments")
		(21 "Eco1.User" user "User.Eco1")
		(23 "Eco2.User" user "User.Eco2")
		(25 "Edge.Cuts" user "Board Geometry/Outline")
		(27 "Margin" user)
		(31 "F.CrtYd" user "Package Geometry/Place Bound Top")
		(29 "B.CrtYd" user "Package Geometry/Place Bound Bottom")
		(35 "F.Fab" user "Ref Des/Assembly Top")
		(33 "B.Fab" user "Ref Des/Assembly Bottom")
	)
	(footprint ""
		(layer "F.Cu")
		(at 48.807116 -344.801952 180)
		(property "Reference" "Q58"
			(at 0 0 180)
			(layer "F.SilkS")
			(hide yes)
			(effects
				(font
					(size 1.27 1.27)
				)
			)
		)
		(property "Value" "2N7002A-7-GP"
			(at 0.127 -8.9662 180)
			(unlocked yes)
			(layer "F.Fab")
			(hide yes)
			(effects
				(font
					(size 1.016 1.016)
					(thickness 0.1524)
				)
			)
		)
		(property "Device Type" "SOT23DGS2D4H48"
			(at 0.127 -10.4902 180)
			(unlocked yes)
			(layer "F.Fab")
			(hide yes)
			(effects
				(font
					(size 1.016 1.016)
					(thickness 0.1524)
				)
			)
		)
		(duplicate_pad_numbers_are_jumpers no)
		(fp_line
			(start 1.651 1.778)
			(end 1.651 -1.778)
			(stroke
				(width 0.1524)
				(type default)
			)
			(layer "F.SilkS")
		)
		(fp_line
			(start 1.651 -1.778)
			(end -1.651 -1.778)
			(stroke
				(width 0.1524)
				(type default)
			)
			(layer "F.SilkS")
		)
		(fp_line
			(start -1.651 1.778)
			(end 1.651 1.778)
			(stroke
				(width 0.1524)
				(type default)
			)
			(layer "F.SilkS")
		)
		(fp_line
			(start -1.651 -1.778)
			(end -1.651 1.778)
			(stroke
				(width 0.1524)
				(type default)
			)
			(layer "F.SilkS")
		)
		(fp_poly
			(pts
				(xy -1.778 1.8796) (xy -1.778 -1.8796) (xy 1.778 -1.8796) (xy 1.778 1.8796)
			)
			(stroke
				(width 0)
				(type default)
			)
			(fill no)
			(layer "F.CrtYd")
		)
		(fp_poly
			(pts
				(xy -1.778 1.8796) (xy -1.778 -1.8796) (xy 1.778 -1.8796) (xy 1.778 1.8796)
			)
			(stroke
				(width 0)
				(type default)
			)
			(fill no)
			(layer "F.Fab")
		)
		(pad "D" smd custom
			(at 0 -0.9525 180)
			(size 0.1905 0.1905)
			(layers "F.Cu" "F.Mask" "F.Paste")
			(net "SSD_ACT_DR6_MOS_N")
			(options
				(clearance outline)
				(anchor circle)
			)
			(primitives
				(gr_poly
					(pts
						(arc
							(start -0.1778 0.5715)
							(mid -0.321484 0.511984)
							(end -0.381 0.3683)
						)
						(arc
							(start -0.381 -0.3683)
							(mid -0.321484 -0.511984)
							(end -0.1778 -0.5715)
						)
						(arc
							(start 0.1778 -0.5715)
							(mid 0.321484 -0.511984)
							(end 0.381 -0.3683)
						)
						(arc
							(start 0.381 0.3683)
							(mid 0.321484 0.511984)
							(end 0.1778 0.5715)
						)
					)
					(width 0)
					(fill yes)
				)
			)
		)
		(pad "G" smd custom
			(at -0.98425 0.9525 180)
			(size 0.1905 0.1905)
			(layers "F.Cu" "F.Mask" "F.Paste")
			(net "ATTN_LED_DR6_AND_R")
			(options
				(clearance outline)
				(anchor circle)
			)
			(primitives
				(gr_poly
					(pts
						(arc
							(start -0.1778 0.5715)
							(mid -0.321484 0.511984)
							(end -0.381 0.3683)
						)
						(arc
							(start -0.381 -0.3683)
							(mid -0.321484 -0.511984)
							(end -0.1778 -0.5715)
						)
						(arc
							(start 0.1778 -0.5715)
							(mid 0.321484 -0.511984)
							(end 0.381 -0.3683)
						)
						(arc
							(start 0.381 0.3683)
							(mid 0.321484 0.511984)
							(end 0.1778 0.5715)
						)
					)
					(width 0)
					(fill yes)
				)
			)
		)
		(pad "S" smd custom
			(at 0.98425 0.9525 180)
			(size 0.1905 0.1905)
			(layers "F.Cu" "F.Mask" "F.Paste")
			(net "SSD_ACT_DR6_R")
			(options
				(clearance outline)
				(anchor circle)
			)
			(primitives
				(gr_poly
					(pts
						(arc
							(start -0.1778 0.5715)
							(mid -0.321484 0.511984)
							(end -0.381 0.3683)
						)
						(arc
							(start -0.381 -0.3683)
							(mid -0.321484 -0.511984)
							(end -0.1778 -0.5715)
						)
						(arc
							(start 0.1778 -0.5715)
							(mid 0.321484 -0.511984)
							(end 0.381 -0.3683)
						)
						(arc
							(start 0.381 0.3683)
							(mid 0.321484 0.511984)
							(end 0.1778 0.5715)
						)
					)
					(width 0)
					(fill yes)
				)
			)
		)
	)
	(footprint ""
		(layer "F.Cu")
		(at 29.95803 -187.684918)
		(property "Reference" "SR1107"
			(at 0 0 0)
			(layer "F.SilkS")
			(hide yes)
			(effects
				(font
					(size 1.27 1.27)
				)
			)
		)
		(property "Value" "4K7R2F-GP"
			(at 0.064008 -3.993896 0)
			(unlocked yes)
			(layer "F.Fab")
			(hide yes)
			(effects
				(font
					(size 1.016 1.016)
					(thickness 0.1524)
				)
			)
		)
		(property "Device Type" "R402H16"
			(at 0.064008 -5.517896 0)
			(unlocked yes)
			(layer "F.Fab")
			(hide yes)
			(effects
				(font
					(size 1.016 1.016)
					(thickness 0.1524)
				)
			)
		)
		(duplicate_pad_numbers_are_jumpers no)
		(fp_line
			(start -0.508 -0.9398)
			(end -0.508 0.9398)
			(stroke
				(width 0.1524)
				(type default)
			)
			(layer "F.SilkS")
		)
		(fp_line
			(start 0.508 -0.9398)
			(end -0.508 -0.9398)
			(stroke
				(width 0.1524)
				(type default)
			)
			(layer "F.SilkS")
		)
		(fp_rect
			(start -0.508 0.9398)
			(end 0.508 -0.9398)
			(stroke
				(width 0)
				(type default)
			)
			(fill no)
			(layer "F.CrtYd")
		)
		(fp_rect
			(start -0.508 0.9398)
			(end 0.508 -0.9398)
			(stroke
				(width 0)
				(type default)
			)
			(fill no)
			(layer "F.Fab")
		)
		(pad "1" smd custom
			(at 0 -0.4445)
			(size 0.1397 0.1397)
			(layers "F.Cu" "F.Mask" "F.Paste")
			(net "P3V3")
			(options
				(clearance outline)
				(anchor circle)
			)
			(primitives
				(gr_poly
					(pts
						(arc
							(start -0.1778 -0.2794)
							(mid -0.249642 -0.249642)
							(end -0.2794 -0.1778)
						)
						(arc
							(start -0.2794 0.1778)
							(mid -0.249642 0.249642)
							(end -0.1778 0.2794)
						)
						(arc
							(start 0.1778 0.2794)
							(mid 0.249642 0.249642)
							(end 0.2794 0.1778)
						)
						(arc
							(start 0.2794 -0.1778)
							(mid 0.249642 -0.249642)
							(end 0.1778 -0.2794)
						)
					)
					(width 0)
					(fill yes)
				)
			)
		)
		(pad "2" smd custom
			(at 0 0.4445)
			(size 0.1397 0.1397)
			(layers "F.Cu" "F.Mask" "F.Paste")
			(net "DUALPORTEN#8")
			(options
				(clearance outline)
				(anchor circle)
			)
			(primitives
				(gr_poly
					(pts
						(arc
							(start -0.1778 -0.2794)
							(mid -0.249642 -0.249642)
							(end -0.2794 -0.1778)
						)
						(arc
							(start -0.2794 0.1778)
							(mid -0.249642 0.249642)
							(end -0.1778 0.2794)
						)
						(arc
							(start 0.1778 0.2794)
							(mid 0.249642 0.249642)
							(end 0.2794 0.1778)
						)
						(arc
							(start 0.2794 -0.1778)
							(mid 0.249642 -0.249642)
							(end 0.1778 -0.2794)
						)
					)
					(width 0)
					(fill yes)
				)
			)
		)
	)
	(footprint ""
		(layer "F.Cu")
		(at 81.788 -146.431 -90)
		(property "Reference" "R428"
			(at 0 0 270)
			(layer "F.SilkS")
			(hide yes)
			(effects
				(font
					(size 1.27 1.27)
				)
			)
		)
		(property "Value" "0R2J-2-GP"
			(at 0.064008 -3.993896 270)
			(unlocked yes)
			(layer "F.Fab")
			(hide yes)
			(effects
				(font
					(size 1.016 1.016)
					(thickness 0.1524)
				)
			)
		)
		(property "Device Type" "R402H16"
			(at 0.064008 -5.517896 270)
			(unlocked yes)
			(layer "F.Fab")
			(hide yes)
			(effects
				(font
					(size 1.016 1.016)
					(thickness 0.1524)
				)
			)
		)
		(duplicate_pad_numbers_are_jumpers no)
		(fp_line
			(start -0.508 -0.9398)
			(end -0.508 0.9398)
			(stroke
				(width 0.1524)
				(type default)
			)
			(layer "F.SilkS")
		)
		(fp_line
			(start 0.508 -0.9398)
			(end -0.508 -0.9398)
			(stroke
				(width 0.1524)
				(type default)
			)
			(layer "F.SilkS")
		)
		(fp_rect
			(start -0.508 0.9398)
			(end 0.508 -0.9398)
			(stroke
				(width 0)
				(type default)
			)
			(fill no)
			(layer "F.CrtYd")
		)
		(fp_rect
			(start -0.508 0.9398)
			(end 0.508 -0.9398)
			(stroke
				(width 0)
				(type default)
			)
			(fill no)
			(layer "F.Fab")
		)
		(pad "1" smd custom
			(at 0 -0.4445 270)
			(size 0.1397 0.1397)
			(layers "F.Cu" "F.Mask" "F.Paste")
			(net "BMC_I2C_SDA_BUF_8")
			(options
				(clearance outline)
				(anchor circle)
			)
			(primitives
				(gr_poly
					(pts
						(arc
							(start -0.1778 -0.2794)
							(mid -0.249642 -0.249642)
							(end -0.2794 -0.1778)
						)
						(arc
							(start -0.2794 0.1778)
							(mid -0.249642 0.249642)
							(end -0.1778 0.2794)
						)
						(arc
							(start 0.1778 0.2794)
							(mid 0.249642 0.249642)
							(end 0.2794 0.1778)
						)
						(arc
							(start 0.2794 -0.1778)
							(mid 0.249642 -0.249642)
							(end 0.1778 -0.2794)
						)
					)
					(width 0)
					(fill yes)
				)
			)
		)
		(pad "2" smd custom
			(at 0 0.4445 270)
			(size 0.1397 0.1397)
			(layers "F.Cu" "F.Mask" "F.Paste")
			(net "I2C8_SDA_R_SW_EU16")
			(options
				(clearance outline)
				(anchor circle)
			)
			(primitives
				(gr_poly
					(pts
						(arc
							(start -0.1778 -0.2794)
							(mid -0.249642 -0.249642)
							(end -0.2794 -0.1778)
						)
						(arc
							(start -0.2794 0.1778)
							(mid -0.249642 0.249642)
							(end -0.1778 0.2794)
						)
						(arc
							(start 0.1778 0.2794)
							(mid 0.249642 0.249642)
							(end 0.2794 0.1778)
						)
						(arc
							(start 0.2794 -0.1778)
							(mid 0.249642 -0.249642)
							(end 0.1778 -0.2794)
						)
					)
					(width 0)
					(fill yes)
				)
			)
		)
	)
	(footprint ""
		(layer "F.Cu")
		(at 18.50009 -464.90001)
		(property "Reference" "LED10"
			(at 0 0 0)
			(layer "F.SilkS")
			(hide yes)
			(effects
				(font
					(size 1.27 1.27)
				)
			)
		)
		(property "Value" "LED-RB-4-GP"
			(at 5.88899 1.80848 0)
			(unlocked yes)
			(layer "F.Fab")
			(hide yes)
			(effects
				(font
					(size 1.016 1.016)
					(thickness 0.1524)
				)
			)
		)
		(property "Device Type" "LED1613-4PH20"
			(at 5.88899 0.28448 0)
			(unlocked yes)
			(layer "F.Fab")
			(hide yes)
			(effects
				(font
					(size 1.016 1.016)
					(thickness 0.1524)
				)
			)
		)
		(duplicate_pad_numbers_are_jumpers no)
		(fp_line
			(start -1.4478 -0.9652)
			(end 1.4478 -0.9652)
			(stroke
				(width 0.1524)
				(type default)
			)
			(layer "F.SilkS")
		)
		(fp_line
			(start -1.4478 0.9652)
			(end -1.4478 -0.9652)
			(stroke
				(width 0.1524)
				(type default)
			)
			(layer "F.SilkS")
		)
		(fp_line
			(start -1.4478 0.9652)
			(end -1.4478 -0.9652)
			(stroke
				(width 0.508)
				(type default)
			)
			(layer "F.SilkS")
		)
		(fp_line
			(start 1.4478 -0.9652)
			(end 1.4478 0.9652)
			(stroke
				(width 0.1524)
				(type default)
			)
			(layer "F.SilkS")
		)
		(fp_line
			(start 1.4478 0.9652)
			(end -1.4478 0.9652)
			(stroke
				(width 0.1524)
				(type default)
			)
			(layer "F.SilkS")
		)
		(fp_rect
			(start -0.8001 0.6477)
			(end 0.8001 -0.6477)
			(stroke
				(width 0)
				(type default)
			)
			(fill no)
			(layer "F.CrtYd")
		)
		(fp_poly
			(pts
				(xy -1.7018 1.2192) (xy -1.7018 -0.06223) (xy -0.8001 -0.06223) (xy -0.8001 0.6477) (xy 0.8001 0.6477)
				(xy 0.8001 -0.6477) (xy -0.8001 -0.6477) (xy -0.8001 -0.0635) (xy -1.7018 -0.0635) (xy -1.7018 -1.2192)
				(xy 1.7018 -1.2192) (xy 1.7018 1.2192)
			)
			(stroke
				(width 0)
				(type default)
			)
			(fill no)
			(layer "F.CrtYd")
		)
		(fp_rect
			(start -1.7018 1.2192)
			(end 1.7018 -1.2192)
			(stroke
				(width 0)
				(type default)
			)
			(fill no)
			(layer "F.Fab")
		)
		(pad "1" smd rect
			(at -0.73025 0.4064)
			(size 0.9144 0.6096)
			(layers "F.Cu" "F.Mask" "F.Paste")
			(net "SSD_ACT_DR10_MOS_N")
		)
		(pad "2" smd rect
			(at -0.73025 -0.4064)
			(size 0.9144 0.6096)
			(layers "F.Cu" "F.Mask" "F.Paste")
			(net "ATTN_LED_DR10_MOS_N")
		)
		(pad "3" smd rect
			(at 0.73025 -0.4064)
			(size 0.9144 0.6096)
			(layers "F.Cu" "F.Mask" "F.Paste")
			(net "DRV_ATTN_10")
		)
		(pad "4" smd rect
			(at 0.73025 0.4064)
			(size 0.9144 0.6096)
			(layers "F.Cu" "F.Mask" "F.Paste")
			(net "DRV_ACT_10")
		)
	)
	(footprint ""
		(layer "F.Cu")
		(at 84.455 -97.79 90)
		(property "Reference" "R426"
			(at 0 0 90)
			(layer "F.SilkS")
			(hide yes)
			(effects
				(font
					(size 1.27 1.27)
				)
			)
		)
		(property "Value" "0R2J-2-GP"
			(at 0.064008 -3.993896 90)
			(unlocked yes)
			(layer "F.Fab")
			(hide yes)
			(effects
				(font
					(size 1.016 1.016)
					(thickness 0.1524)
				)
			)
		)
		(property "Device Type" "R402H16"
			(at 0.064008 -5.517896 90)
			(unlocked yes)
			(layer "F.Fab")
			(hide yes)
			(effects
				(font
					(size 1.016 1.016)
					(thickness 0.1524)
				)
			)
		)
		(duplicate_pad_numbers_are_jumpers no)
		(fp_line
			(start 0.508 -0.9398)
			(end -0.508 -0.9398)
			(stroke
				(width 0.1524)
				(type default)
			)
			(layer "F.SilkS")
		)
		(fp_line
			(start -0.508 -0.9398)
			(end -0.508 0.9398)
			(stroke
				(width 0.1524)
				(type default)
			)
			(layer "F.SilkS")
		)
		(fp_rect
			(start -0.508 0.9398)
			(end 0.508 -0.9398)
			(stroke
				(width 0)
				(type default)
			)
			(fill no)
			(layer "F.CrtYd")
		)
		(fp_rect
			(start -0.508 0.9398)
			(end 0.508 -0.9398)
			(stroke
				(width 0)
				(type default)
			)
			(fill no)
			(layer "F.Fab")
		)
		(pad "1" smd custom
			(at 0 -0.4445 90)
			(size 0.1397 0.1397)
			(layers "F.Cu" "F.Mask" "F.Paste")
			(net "BMC_I2C_SDA_BUF_8")
			(options
				(clearance outline)
				(anchor circle)
			)
			(primitives
				(gr_poly
					(pts
						(arc
							(start -0.1778 -0.2794)
							(mid -0.249642 -0.249642)
							(end -0.2794 -0.1778)
						)
						(arc
							(start -0.2794 0.1778)
							(mid -0.249642 0.249642)
							(end -0.1778 0.2794)
						)
						(arc
							(start 0.1778 0.2794)
							(mid 0.249642 0.249642)
							(end 0.2794 0.1778)
						)
						(arc
							(start 0.2794 -0.1778)
							(mid 0.249642 -0.249642)
							(end 0.1778 -0.2794)
						)
					)
					(width 0)
					(fill yes)
				)
			)
		)
		(pad "2" smd custom
			(at 0 0.4445 90)
			(size 0.1397 0.1397)
			(layers "F.Cu" "F.Mask" "F.Paste")
			(net "I2C_SDA_BUF_8_EU4_R")
			(options
				(clearance outline)
				(anchor circle)
			)
			(primitives
				(gr_poly
					(pts
						(arc
							(start -0.1778 -0.2794)
							(mid -0.249642 -0.249642)
							(end -0.2794 -0.1778)
						)
						(arc
							(start -0.2794 0.1778)
							(mid -0.249642 0.249642)
							(end -0.1778 0.2794)
						)
						(arc
							(start 0.1778 0.2794)
							(mid 0.249642 0.249642)
							(end 0.2794 0.1778)
						)
						(arc
							(start 0.2794 -0.1778)
							(mid 0.249642 -0.249642)
							(end 0.1778 -0.2794)
						)
					)
					(width 0)
					(fill yes)
				)
			)
		)
	)
	(footprint ""
		(layer "F.Cu")
		(at 8.8138 -467.5124 90)
		(property "Reference" "PC1168"
			(at 0 0 90)
			(layer "F.SilkS")
			(hide yes)
			(effects
				(font
					(size 1.27 1.27)
				)
			)
		)
		(property "Value" "SC22U25V6KX-GP-U"
			(at -2.860802 -5.279644 90)
			(unlocked yes)
			(layer "F.Fab")
			(hide yes)
			(effects
				(font
					(size 1.016 1.016)
					(thickness 0.1524)
				)
			)
		)
		(property "Device Type" "C1206-TO0D3H75"
			(at -2.860802 -6.803644 90)
			(unlocked yes)
			(layer "F.Fab")
			(hide yes)
			(effects
				(font
					(size 1.016 1.016)
					(thickness 0.1524)
				)
			)
		)
		(duplicate_pad_numbers_are_jumpers no)
		(fp_line
			(start 1.3081 -2.3749)
			(end 1.3081 2.3749)
			(stroke
				(width 0.1524)
				(type default)
			)
			(layer "F.SilkS")
		)
		(fp_line
			(start -1.3081 -2.3749)
			(end 1.3081 -2.3749)
			(stroke
				(width 0.1524)
				(type default)
			)
			(layer "F.SilkS")
		)
		(fp_line
			(start 1.3081 2.3749)
			(end -1.3081 2.3749)
			(stroke
				(width 0.1524)
				(type default)
			)
			(layer "F.SilkS")
		)
		(fp_line
			(start -1.3081 2.3749)
			(end -1.3081 -2.3749)
			(stroke
				(width 0.1524)
				(type default)
			)
			(layer "F.SilkS")
		)
		(fp_rect
			(start -0.8001 1.6002)
			(end 0.8001 -1.6002)
			(stroke
				(width 0)
				(type default)
			)
			(fill no)
			(layer "F.CrtYd")
		)
		(fp_poly
			(pts
				(xy -1.5621 2.4511) (xy -1.5621 1.6002) (xy 0.8001 1.6002) (xy 0.8001 -1.6002) (xy -0.8001 -1.6002)
				(xy -0.8001 1.5875) (xy -1.5621 1.5875) (xy -1.5621 -2.4511) (xy 1.5621 -2.4511) (xy 1.5621 2.4511)
			)
			(stroke
				(width 0)
				(type default)
			)
			(fill no)
			(layer "F.CrtYd")
		)
		(fp_rect
			(start -1.5621 2.4511)
			(end 1.5621 -2.4511)
			(stroke
				(width 0)
				(type default)
			)
			(fill no)
			(layer "F.Fab")
		)
		(pad "1" smd rect
			(at 0 -1.392936 90)
			(size 2.1082 1.4478)
			(layers "F.Cu" "F.Mask" "F.Paste")
			(net "P12V")
		)
		(pad "2" smd rect
			(at 0 1.392936 90)
			(size 2.1082 1.4478)
			(layers "F.Cu" "F.Mask" "F.Paste")
			(net "GND")
		)
	)
	(footprint ""
		(layer "F.Cu")
		(at 97.028 -26.162 180)
		(property "Reference" "R9757"
			(at 0 0 180)
			(layer "F.SilkS")
			(hide yes)
			(effects
				(font
					(size 1.27 1.27)
				)
			)
		)
		(property "Value" "0R2J-2-GP"
			(at 0.064008 -3.993896 180)
			(unlocked yes)
			(layer "F.Fab")
			(hide yes)
			(effects
				(font
					(size 1.016 1.016)
					(thickness 0.1524)
				)
			)
		)
		(property "Device Type" "R402H16"
			(at 0.064008 -5.517896 180)
			(unlocked yes)
			(layer "F.Fab")
			(hide yes)
			(effects
				(font
					(size 1.016 1.016)
					(thickness 0.1524)
				)
			)
		)
		(duplicate_pad_numbers_are_jumpers no)
		(fp_line
			(start 0.508 -0.9398)
			(end -0.508 -0.9398)
			(stroke
				(width 0.1524)
				(type default)
			)
			(layer "F.SilkS")
		)
		(fp_line
			(start -0.508 -0.9398)
			(end -0.508 0.9398)
			(stroke
				(width 0.1524)
				(type default)
			)
			(layer "F.SilkS")
		)
		(fp_rect
			(start -0.508 0.9398)
			(end 0.508 -0.9398)
			(stroke
				(width 0)
				(type default)
			)
			(fill no)
			(layer "F.CrtYd")
		)
		(fp_rect
			(start -0.508 0.9398)
			(end 0.508 -0.9398)
			(stroke
				(width 0)
				(type default)
			)
			(fill no)
			(layer "F.Fab")
		)
		(pad "1" smd custom
			(at 0 -0.4445 180)
			(size 0.1397 0.1397)
			(layers "F.Cu" "F.Mask" "F.Paste")
			(net "P3V3")
			(options
				(clearance outline)
				(anchor circle)
			)
			(primitives
				(gr_poly
					(pts
						(arc
							(start -0.1778 -0.2794)
							(mid -0.249642 -0.249642)
							(end -0.2794 -0.1778)
						)
						(arc
							(start -0.2794 0.1778)
							(mid -0.249642 0.249642)
							(end -0.1778 0.2794)
						)
						(arc
							(start 0.1778 0.2794)
							(mid 0.249642 0.249642)
							(end 0.2794 0.1778)
						)
						(arc
							(start 0.2794 -0.1778)
							(mid 0.249642 -0.249642)
							(end 0.1778 -0.2794)
						)
					)
					(width 0)
					(fill yes)
				)
			)
		)
		(pad "2" smd custom
			(at 0 0.4445 180)
			(size 0.1397 0.1397)
			(layers "F.Cu" "F.Mask" "F.Paste")
			(net "P3V3_SENSE")
			(options
				(clearance outline)
				(anchor circle)
			)
			(primitives
				(gr_poly
					(pts
						(arc
							(start -0.1778 -0.2794)
							(mid -0.249642 -0.249642)
							(end -0.2794 -0.1778)
						)
						(arc
							(start -0.2794 0.1778)
							(mid -0.249642 0.249642)
							(end -0.1778 0.2794)
						)
						(arc
							(start 0.1778 0.2794)
							(mid 0.249642 0.249642)
							(end 0.2794 0.1778)
						)
						(arc
							(start 0.2794 -0.1778)
							(mid 0.249642 -0.249642)
							(end 0.1778 -0.2794)
						)
					)
					(width 0)
					(fill yes)
				)
			)
		)
	)
)
